#ISCELL
  pure_quanta quanta_title_block_c *
  *
#CELL
  pure_quanta pt5161lrs *
  page384_i1
#ISCELL
  standard tap *
  page384_i10
#CELL
  pure_quanta q_cap_diffbus *
  page384_i100
#CELL
  pure_quanta q_cap_diffbus *
  page384_i101
#CELL
  pure_quanta q_cap_diffbus *
  page384_i102
#ISCELL
  standard tap *
  page384_i103
#ISCELL
  standard tap *
  page384_i104
#ISCELL
  standard tap *
  page384_i105
#ISCELL
  standard tap *
  page384_i106
#ISCELL
  standard tap *
  page384_i107
#ISCELL
  standard tap *
  page384_i108
#ISCELL
  standard tap *
  page384_i109
#ISCELL
  standard tap *
  page384_i11
#ISCELL
  standard tap *
  page384_i110
#ISCELL
  standard tap *
  page384_i111
#ISCELL
  standard tap *
  page384_i112
#ISCELL
  standard tap *
  page384_i113
#ISCELL
  standard tap *
  page384_i114
#ISCELL
  standard tap *
  page384_i115
#ISCELL
  standard tap *
  page384_i116
#ISCELL
  standard tap *
  page384_i117
#CELL
  pure_quanta q_cap_diffbus *
  page384_i118
#CELL
  pure_quanta q_cap_diffbus *
  page384_i119
#ISCELL
  standard tap *
  page384_i12
#CELL
  pure_quanta q_cap_diffbus *
  page384_i120
#CELL
  pure_quanta q_cap_diffbus *
  page384_i121
#CELL
  pure_quanta q_cap_diffbus *
  page384_i122
#CELL
  pure_quanta q_cap_diffbus *
  page384_i123
#CELL
  pure_quanta q_cap_diffbus *
  page384_i124
#CELL
  pure_quanta q_cap_diffbus *
  page384_i125
#CELL
  pure_quanta q_cap_diffbus *
  page384_i126
#CELL
  pure_quanta q_cap_diffbus *
  page384_i127
#ISCELL
  standard tap *
  page384_i128
#CELL
  pure_quanta q_cap_diffbus *
  page384_i129
#ISCELL
  standard tap *
  page384_i13
#CELL
  pure_quanta q_cap_diffbus *
  page384_i130
#ISCELL
  standard tap *
  page384_i131
#ISCELL
  standard tap *
  page384_i132
#ISCELL
  standard tap *
  page384_i133
#ISCELL
  standard tap *
  page384_i134
#ISCELL
  standard tap *
  page384_i135
#ISCELL
  standard tap *
  page384_i136
#ISCELL
  standard tap *
  page384_i137
#ISCELL
  standard tap *
  page384_i138
#ISCELL
  standard tap *
  page384_i139
#ISCELL
  standard tap *
  page384_i14
#ISCELL
  standard tap *
  page384_i140
#ISCELL
  standard tap *
  page384_i141
#ISCELL
  standard tap *
  page384_i142
#ISCELL
  standard offpage *
  page384_i143
#ISCELL
  standard offpage *
  page384_i144
#ISCELL
  standard tap *
  page384_i15
#ISCELL
  standard tap *
  page384_i16
#ISCELL
  standard tap *
  page384_i19
#CELL
  pure_quanta pt5161lrs *
  page384_i2
#ISCELL
  standard tap *
  page384_i20
#ISCELL
  standard offpage *
  page384_i21
#ISCELL
  standard offpage *
  page384_i22
#ISCELL
  standard offpage *
  page384_i23
#ISCELL
  standard offpage *
  page384_i24
#ISCELL
  standard tap *
  page384_i25
#ISCELL
  standard tap *
  page384_i26
#ISCELL
  standard tap *
  page384_i27
#ISCELL
  standard tap *
  page384_i28
#ISCELL
  standard tap *
  page384_i29
#ISCELL
  standard tap *
  page384_i3
#ISCELL
  standard tap *
  page384_i30
#ISCELL
  standard tap *
  page384_i31
#ISCELL
  standard tap *
  page384_i32
#ISCELL
  standard tap *
  page384_i33
#ISCELL
  standard tap *
  page384_i34
#ISCELL
  standard tap *
  page384_i35
#ISCELL
  standard tap *
  page384_i36
#ISCELL
  standard tap *
  page384_i37
#ISCELL
  standard tap *
  page384_i38
#ISCELL
  standard tap *
  page384_i39
#ISCELL
  standard tap *
  page384_i4
#ISCELL
  standard tap *
  page384_i40
#ISCELL
  standard offpage *
  page384_i41
#ISCELL
  standard offpage *
  page384_i42
#ISCELL
  standard tap *
  page384_i43
#ISCELL
  standard tap *
  page384_i44
#ISCELL
  standard tap *
  page384_i45
#ISCELL
  standard tap *
  page384_i46
#ISCELL
  standard tap *
  page384_i47
#ISCELL
  standard tap *
  page384_i48
#ISCELL
  standard tap *
  page384_i49
#ISCELL
  standard tap *
  page384_i5
#ISCELL
  standard tap *
  page384_i50
#ISCELL
  standard tap *
  page384_i51
#ISCELL
  standard tap *
  page384_i52
#ISCELL
  standard tap *
  page384_i53
#ISCELL
  standard tap *
  page384_i54
#ISCELL
  standard tap *
  page384_i55
#ISCELL
  standard tap *
  page384_i56
#ISCELL
  standard tap *
  page384_i57
#ISCELL
  standard tap *
  page384_i58
#CELL
  pure_quanta q_cap_diffbus *
  page384_i59
#ISCELL
  standard tap *
  page384_i6
#CELL
  pure_quanta q_cap_diffbus *
  page384_i60
#CELL
  pure_quanta q_cap_diffbus *
  page384_i61
#CELL
  pure_quanta q_cap_diffbus *
  page384_i62
#CELL
  pure_quanta q_cap_diffbus *
  page384_i63
#CELL
  pure_quanta q_cap_diffbus *
  page384_i64
#CELL
  pure_quanta q_cap_diffbus *
  page384_i65
#CELL
  pure_quanta q_cap_diffbus *
  page384_i66
#ISCELL
  standard tap *
  page384_i67
#ISCELL
  standard tap *
  page384_i68
#ISCELL
  standard tap *
  page384_i69
#ISCELL
  standard tap *
  page384_i7
#ISCELL
  standard tap *
  page384_i70
#CELL
  pure_quanta q_cap_diffbus *
  page384_i71
#CELL
  pure_quanta q_cap_diffbus *
  page384_i72
#CELL
  pure_quanta q_cap_diffbus *
  page384_i73
#CELL
  pure_quanta q_cap_diffbus *
  page384_i74
#CELL
  pure_quanta q_cap_diffbus *
  page384_i75
#CELL
  pure_quanta q_cap_diffbus *
  page384_i76
#CELL
  pure_quanta q_cap_diffbus *
  page384_i77
#CELL
  pure_quanta q_cap_diffbus *
  page384_i78
#ISCELL
  standard tap *
  page384_i79
#ISCELL
  standard tap *
  page384_i8
#ISCELL
  standard tap *
  page384_i80
#ISCELL
  standard tap *
  page384_i81
#ISCELL
  standard tap *
  page384_i82
#ISCELL
  standard tap *
  page384_i83
#ISCELL
  standard tap *
  page384_i84
#ISCELL
  standard tap *
  page384_i85
#ISCELL
  standard tap *
  page384_i86
#ISCELL
  standard tap *
  page384_i87
#ISCELL
  standard tap *
  page384_i88
#ISCELL
  standard offpage *
  page384_i89
#ISCELL
  standard tap *
  page384_i9
#ISCELL
  standard offpage *
  page384_i90
#ISCELL
  standard tap *
  page384_i91
#ISCELL
  standard tap *
  page384_i92
#ISCELL
  standard offpage *
  page384_i93
#ISCELL
  standard offpage *
  page384_i94
#ISCELL
  standard tap *
  page384_i95
#ISCELL
  standard tap *
  page384_i96
#ISCELL
  standard tap *
  page384_i97
#ISCELL
  standard tap *
  page384_i98
#CELL
  pure_quanta q_cap_diffbus *
  page384_i99
